# T6G (Grand Teton) — schematic netlist excerpt (pin names and nets, part order shuffled) for the footprints in the layout excerpt that follows; sources: Cadence DE-HDL packaged netlist, KiCad conversion of 04192023_DAF0TMB3IC0_F0TG_MB_C_brd_V02_OCP.brd

R6776  Q_RES  0 5% CHIP  pkg 0201LF  page 184 : A = RST_SMB_RT_R1_N ; B = RST_SMB_RT_N
R3958  Q_RES  0 5% CHIP  pkg 0402LF  page 146 : A = P12V_E1S_UV_0_R ; B = P12V_E1S_UV_0
C392  Q_CAP  0.1UF 10V 10% X7S  pkg C0201  page 345 : A = P0V9_CPU1_RT_2D ; B = GND

(kicad_pcb
	(version 20260206)
	(generator "pcbnew")
	(generator_version "10.0")
	(general
		(thickness 1.6)
		(legacy_teardrops no)
	)
	(paper "A4")
	(title_block
		(title "04192023_DAF0TMB3IC0_F0TG_MB_C_brd_V02_OCP.brd")
		(comment 1 "Grand Teton / footprints 8082-8084 of 8354")
	)
	(layers
		(0 "F.Cu" signal "TOP")
		(4 "In1.Cu" signal "GND")
		(6 "In2.Cu" signal "IN1")
		(8 "In3.Cu" signal "GND1")
		(10 "In4.Cu" signal "IN2")
		(12 "In5.Cu" signal "GND2")
		(14 "In6.Cu" signal "IN3")
		(16 "In7.Cu" signal "GND3")
		(18 "In8.Cu" signal "VCC")
		(20 "In9.Cu" signal "VCC1")
		(22 "In10.Cu" signal "GND4")
		(24 "In11.Cu" signal "IN4")
		(26 "In12.Cu" signal "GND5")
		(28 "In13.Cu" signal "IN5")
		(30 "In14.Cu" signal "GND6")
		(32 "In15.Cu" signal "IN6")
		(34 "In16.Cu" signal "GND7")
		(2 "B.Cu" signal "BOTTOM")
		(9 "F.Adhes" user "F.Adhesive")
		(11 "B.Adhes" user "B.Adhesive")
		(13 "F.Paste" user "Package Geometry/Pastemask Top")
		(15 "B.Paste" user "Package Geometry/Pastemask Bottom")
		(5 "F.SilkS" user "Ref Des/Silkscreen Top")
		(7 "B.SilkS" user "Ref Des/Silkscreen Bottom")
		(1 "F.Mask" user "Board Geometry/Soldermask Top")
		(3 "B.Mask" user "Board Geometry/Soldermask Bottom")
		(17 "Dwgs.User" user "User.Drawings")
		(19 "Cmts.User" user "User.Comments")
		(21 "Eco1.User" user "User.Eco1")
		(23 "Eco2.User" user "User.Eco2")
		(25 "Edge.Cuts" user "Board Geometry/Outline")
		(27 "Margin" user)
		(31 "F.CrtYd" user "Package Geometry/Place Bound Top")
		(29 "B.CrtYd" user "Package Geometry/Place Bound Bottom")
		(35 "F.Fab" user "Ref Des/Assembly Top")
		(33 "B.Fab" user "Ref Des/Assembly Bottom")
	)
	(footprint ""
		(layer "B.Cu")
		(at 250.07697 -45.461682 90)
		(property "Reference" "R3958"
			(at 0 0 90)
			(layer "B.SilkS")
			(hide yes)
			(effects
				(font
					(size 1.27 1.27)
				)
				(justify mirror)
			)
		)
		(property "Value" ""
			(at 0 0 90)
			(layer "B.Fab")
			(effects
				(font
					(size 1.27 1.27)
				)
				(justify mirror)
			)
		)
		(duplicate_pad_numbers_are_jumpers no)
		(fp_line
			(start 0.7874 -0.4064)
			(end -0.7874 -0.4064)
			(stroke
				(width 0.1524)
				(type default)
			)
			(layer "B.SilkS")
		)
		(fp_line
			(start -0.7874 -0.4064)
			(end -0.7874 0.4064)
			(stroke
				(width 0.1524)
				(type default)
			)
			(layer "B.SilkS")
		)
		(fp_line
			(start 0.7874 0.4064)
			(end 0.7874 -0.4064)
			(stroke
				(width 0.1524)
				(type default)
			)
			(layer "B.SilkS")
		)
		(fp_line
			(start -0.7874 0.4064)
			(end 0.7874 0.4064)
			(stroke
				(width 0.1524)
				(type default)
			)
			(layer "B.SilkS")
		)
		(fp_line
			(start 0.67945 -0.305054)
			(end 0.12065 -0.305054)
			(stroke
				(width 0.1)
				(type default)
			)
			(layer "B.Fab")
		)
		(fp_line
			(start 0.12065 -0.305054)
			(end 0.12065 -0.2794)
			(stroke
				(width 0.1)
				(type default)
			)
			(layer "B.Fab")
		)
		(fp_line
			(start -0.12065 -0.3048)
			(end -0.67945 -0.3048)
			(stroke
				(width 0.1)
				(type default)
			)
			(layer "B.Fab")
		)
		(fp_line
			(start -0.67945 -0.3048)
			(end -0.67945 0.3048)
			(stroke
				(width 0.1)
				(type default)
			)
			(layer "B.Fab")
		)
		(fp_line
			(start 0.12065 -0.2794)
			(end -0.12065 -0.2794)
			(stroke
				(width 0.1)
				(type default)
			)
			(layer "B.Fab")
		)
		(fp_line
			(start -0.12065 -0.2794)
			(end -0.12065 -0.3048)
			(stroke
				(width 0.1)
				(type default)
			)
			(layer "B.Fab")
		)
		(fp_line
			(start 0.12065 0.2794)
			(end 0.12065 0.3048)
			(stroke
				(width 0.1)
				(type default)
			)
			(layer "B.Fab")
		)
		(fp_line
			(start -0.120396 0.2794)
			(end 0.12065 0.2794)
			(stroke
				(width 0.1)
				(type default)
			)
			(layer "B.Fab")
		)
		(fp_line
			(start 0.67945 0.3048)
			(end 0.67945 -0.305054)
			(stroke
				(width 0.1)
				(type default)
			)
			(layer "B.Fab")
		)
		(fp_line
			(start 0.12065 0.3048)
			(end 0.67945 0.3048)
			(stroke
				(width 0.1)
				(type default)
			)
			(layer "B.Fab")
		)
		(fp_line
			(start -0.120396 0.3048)
			(end -0.120396 0.2794)
			(stroke
				(width 0.1)
				(type default)
			)
			(layer "B.Fab")
		)
		(fp_line
			(start -0.67945 0.3048)
			(end -0.120396 0.3048)
			(stroke
				(width 0.1)
				(type default)
			)
			(layer "B.Fab")
		)
		(pad "1" smd circle
			(at 0.40005 0 270)
			(size 0 0)
			(layers "B.Cu" "B.Mask" "B.Paste")
			(net "P12V_E1S_UV_0_R")
		)
		(pad "2" smd circle
			(at -0.40005 0 270)
			(size 0 0)
			(layers "B.Cu" "B.Mask" "B.Paste")
			(net "P12V_E1S_UV_0")
		)
	)
	(footprint ""
		(layer "B.Cu")
		(at 217.17 -332.74 180)
		(property "Reference" "R6776"
			(at 0 0 0)
			(layer "B.SilkS")
			(hide yes)
			(effects
				(font
					(size 1.27 1.27)
				)
				(justify mirror)
			)
		)
		(property "Value" ""
			(at 0 0 0)
			(layer "B.Fab")
			(effects
				(font
					(size 1.27 1.27)
				)
				(justify mirror)
			)
		)
		(duplicate_pad_numbers_are_jumpers no)
		(fp_line
			(start 0.32512 0.175006)
			(end 0.32512 -0.175006)
			(stroke
				(width 0.1)
				(type default)
			)
			(layer "B.Fab")
		)
		(fp_line
			(start 0.32512 -0.175006)
			(end -0.32512 -0.175006)
			(stroke
				(width 0.1)
				(type default)
			)
			(layer "B.Fab")
		)
		(fp_line
			(start -0.32512 0.175006)
			(end 0.32512 0.175006)
			(stroke
				(width 0.1)
				(type default)
			)
			(layer "B.Fab")
		)
		(fp_line
			(start -0.32512 -0.175006)
			(end -0.32512 0.175006)
			(stroke
				(width 0.1)
				(type default)
			)
			(layer "B.Fab")
		)
		(pad "1" smd rect
			(at 0.2667 0)
			(size 0.3048 0.381)
			(layers "B.Cu" "B.Mask" "B.Paste")
			(net "RST_SMB_RT_R1_N")
		)
		(pad "2" smd rect
			(at -0.2667 0 180)
			(size 0.3048 0.381)
			(layers "B.Cu" "B.Mask" "B.Paste")
			(net "RST_SMB_RT_N")
		)
	)
	(footprint ""
		(layer "B.Cu")
		(at 159.006286 -386.766562 90)
		(property "Reference" "C392"
			(at 0 0 90)
			(layer "B.SilkS")
			(hide yes)
			(effects
				(font
					(size 1.27 1.27)
				)
				(justify mirror)
			)
		)
		(property "Value" ""
			(at 0 0 90)
			(layer "B.Fab")
			(effects
				(font
					(size 1.27 1.27)
				)
				(justify mirror)
			)
		)
		(duplicate_pad_numbers_are_jumpers no)
		(fp_line
			(start 0.299974 -0.150114)
			(end -0.299974 -0.150114)
			(stroke
				(width 0.1)
				(type default)
			)
			(layer "B.Fab")
		)
		(fp_line
			(start -0.299974 -0.150114)
			(end -0.299974 0.150114)
			(stroke
				(width 0.1)
				(type default)
			)
			(layer "B.Fab")
		)
		(fp_line
			(start 0.299974 0.150114)
			(end 0.299974 -0.150114)
			(stroke
				(width 0.1)
				(type default)
			)
			(layer "B.Fab")
		)
		(fp_line
			(start -0.299974 0.150114)
			(end 0.299974 0.150114)
			(stroke
				(width 0.1)
				(type default)
			)
			(layer "B.Fab")
		)
		(pad "1" smd rect
			(at 0.2667 0 270)
			(size 0.3048 0.381)
			(layers "B.Cu" "B.Mask" "B.Paste")
			(net "P0V9_CPU1_RT_2D")
		)
		(pad "2" smd rect
			(at -0.2667 0 270)
			(size 0.3048 0.381)
			(layers "B.Cu" "B.Mask" "B.Paste")
			(net "GND")
		)
	)
)
